FILE_TYPE = CONNECTIVITY;
{Allegro Design Entry HDL 17.2-2016 S081 (4005846) 1/11/2022}
"PAGE_NUMBER" = 288;
0"NC";
1"T1_GND\g";
2"T1_GND\g";
3"T1_GND\g";
4"T1_GND\g";
5"T1_GND\g";
6"T1_GND\g";
7"T1_GND\g";
8"T1_GND\g";
9"T1_GND\g";
10"T1_GND\g";
11"T1_GND\g";
12"T1_GND\g";
13"T1_GND\g";
14"T1_GND\g";
15"T1_GND\g";
16"T1_GND\g";
17"T1_GND\g";
18"T1_GND\g";
19"T1_GND\g";
20"T1_GND\g";
21"T1_GND\g";
22"T1_GND\g";
23"T1_GND\g";
24"T1_GND\g";
25"T1_GND\g";
26"T1_GND\g";
27"T1_GND\g";
28"T1_GND\g";
29"T1_GND\g";
30"T1_GND\g";
31"T1_GND\g";
32"T1_GND\g";
33"T1_GND\g";
34"T1_GND\g";
35"T1_GND\g";
36"T1_GND\g";
37"T1_GND\g";
38"T1_GND\g";
39"T1_GND\g";
40"T1_GND\g";
41"T1_GND\g";
42"T1_GND\g";
43"T1_GND\g";
44"T1_GND\g";
45"T1_GND\g";
46"T1_GND\g";
47"T1_GND\g";
48"T1_GND\g";
49"TDR_SE_40_OHM_IN6"CDS_PHYS_NET_NAME"TDR_SE_40_OHM_IN4";
50"TDR_SE_50_OHM_BOT"CDS_PHYS_NET_NAME"TDR_SE_50_OHM_BOT";
51"TDR_SE_50_OHM_IN6"CDS_PHYS_NET_NAME"TDR_SE_50_OHM_IN4";
52"TDR_SE_40_OHM_IN3"CDS_PHYS_NET_NAME"TDR_SE_40_OHM_IN3";
53"TDR_DIFF_85_IN3_DP"CDS_PHYS_NET_NAME"TDR_DIFF_85_IN3_DP";
54"TDR_SE_50_OHM_IN1"CDS_PHYS_NET_NAME"TDR_SE_50_OHM_IN1";
55"TDR_SE_50_OHM_IN3"CDS_PHYS_NET_NAME"TDR_SE_50_OHM_IN3";
56"TDR_SE_50_OHM_IN4"CDS_PHYS_NET_NAME"TDR_SE_50_OHM_IN4";
57"TDR_DIFF_100_IN3_DP"CDS_PHYS_NET_NAME"TDR_DIFF_100_IN3_DP";
58"TDR_DIFF_100_IN3_DN"CDS_PHYS_NET_NAME"TDR_DIFF_100_IN3_DN";
59"TDR_DIFF_100_IN4_DN"CDS_PHYS_NET_NAME"TDR_DIFF_100_IN4_DN";
60"TDR_DIFF_100_IN5_DP"CDS_PHYS_NET_NAME"TDR_DIFF_100_IN3_DP";
61"TDR_SE_40_OHM_IN1"CDS_PHYS_NET_NAME"TDR_SE_40_OHM_IN1";
62"TDR_SE_50_OHM_IN2"CDS_PHYS_NET_NAME"TDR_SE_50_OHM_IN2";
63"TDR_DIFF_85_IN5_DN"CDS_PHYS_NET_NAME"TDR_DIFF_85_IN3_DN";
64"TDR_DIFF_85_IN5_DP"CDS_PHYS_NET_NAME"TDR_DIFF_85_IN3_DP";
65"TDR_DIFF_85_IN4_DN"CDS_PHYS_NET_NAME"TDR_DIFF_85_IN4_DN";
66"TDR_DIFF_85_IN4_DP"CDS_PHYS_NET_NAME"TDR_DIFF_85_IN4_DP";
67"TDR_DIFF_85_IN3_DN"CDS_PHYS_NET_NAME"TDR_DIFF_85_IN3_DN";
68"TDR_DIFF_85_IN2_DP"CDS_PHYS_NET_NAME"TDR_DIFF_85_IN2_DP";
69"TDR_DIFF_85_IN1_DP"CDS_PHYS_NET_NAME"TDR_DIFF_85_IN1_DP";
70"TDR_DIFF_85_TOP_DN"CDS_PHYS_NET_NAME"TDR_DIFF_85_TOP_DN";
71"TDR_DIFF_85_TOP_DP"CDS_PHYS_NET_NAME"TDR_DIFF_85_TOP_DP";
72"TDR_DIFF_100_IN2_DN"CDS_PHYS_NET_NAME"TDR_DIFF_100_IN2_DN";
73"TDR_SE_50_OHM_IN5"CDS_PHYS_NET_NAME"TDR_SE_50_OHM_IN3";
74"TDR_DIFF_100_IN6_DP"CDS_PHYS_NET_NAME"TDR_DIFF_100_IN4_DP";
75"TDR_DIFF_100_IN6_DN"CDS_PHYS_NET_NAME"TDR_DIFF_100_IN4_DN";
76"TDR_DIFF_100_BOT_DP"CDS_PHYS_NET_NAME"TDR_DIFF_100_BOT_DP";
77"TDR_DIFF_100_BOT_DN"CDS_PHYS_NET_NAME"TDR_DIFF_100_BOT_DN";
78"TDR_DIFF_100_IN4_DP"CDS_PHYS_NET_NAME"TDR_DIFF_100_IN4_DP";
79"TDR_DIFF_100_IN5_DN"CDS_PHYS_NET_NAME"TDR_DIFF_100_IN3_DN";
80"TDR_DIFF_85_BOT_DN"CDS_PHYS_NET_NAME"TDR_DIFF_85_BOT_DN";
81"TDR_DIFF_85_BOT_DP"CDS_PHYS_NET_NAME"TDR_DIFF_85_BOT_DP";
82"TDR_SE_40_OHM_IN5"CDS_PHYS_NET_NAME"TDR_SE_40_OHM_IN3";
83"TDR_DIFF_85_IN6_DP"CDS_PHYS_NET_NAME"TDR_DIFF_85_IN4_DP";
84"TDR_DIFF_85_IN6_DN"CDS_PHYS_NET_NAME"TDR_DIFF_85_IN4_DN";
85"TDR_DIFF_85_IN2_DN"CDS_PHYS_NET_NAME"TDR_DIFF_85_IN2_DN";
86"TDR_DIFF_100_TOP_DN"CDS_PHYS_NET_NAME"TDR_DIFF_100_TOP_DN";
87"TDR_DIFF_100_TOP_DP"CDS_PHYS_NET_NAME"TDR_DIFF_100_TOP_DP";
88"TDR_DIFF_100_IN1_DN"CDS_PHYS_NET_NAME"TDR_DIFF_100_IN1_DN";
89"TDR_DIFF_100_IN1_DP"CDS_PHYS_NET_NAME"TDR_DIFF_100_IN1_DP";
90"TDR_DIFF_100_IN2_DP"CDS_PHYS_NET_NAME"TDR_DIFF_100_IN2_DP";
91"TDR_DIFF_85_IN1_DN"CDS_PHYS_NET_NAME"TDR_DIFF_85_IN1_DN";
92"TDR_SE_50_OHM_TOP"CDS_PHYS_NET_NAME"TDR_SE_50_OHM_TOP";
93"TDR_SE_40_OHM_TOP"CDS_PHYS_NET_NAME"TDR_SE_40_OHM_TOP";
94"TDR_SE_40_OHM_IN2"CDS_PHYS_NET_NAME"TDR_SE_40_OHM_IN2";
95"TDR_SE_40_OHM_IN4"CDS_PHYS_NET_NAME"TDR_SE_40_OHM_IN4";
96"TDR_SE_40_OHM_BOT"CDS_PHYS_NET_NAME"TDR_SE_40_OHM_BOT";
%"TP_TDR_4P_FTS"
"1","(4725,1150)","4","pure_quanta","I10";
;
PART_NUMBER"TP15"
VALUE"TP_TDR_4P_DIP"
PACK_TYPE"TH"
MATERIAL"EMPTY"
$LOCATION"X23"
NEEDS_NO_SIZE"TRUE"
CDS_LIB"pure_quanta"
CDS_LOCATION"X23"
$SEC"1"
CDS_SEC"1";
"S1"
$PN"1"59;
"P2 \B"
$PN"3"34;
"S2"
$PN"4"78;
"P1 \B"
$PN"2"34;
%"UNIVERSAL_GND"
"1","(-1525,900)","0","logical_power","I100";
;
HDL_POWER"T1_GND"
CDS_LIB"logical_power";
"A"13;
%"TDR_3P"
"2","(-2875,1650)","0","pure_quanta","I101";
;
PART_NUMBER"N_A"
PACK_TYPE"TH2"
$LOCATION"DB13"
MATERIAL"EMPTY"
CDS_LIB"pure_quanta"
CDS_LMAN_SYM_OUTLINE"-150,100,50,-100"
CDS_LOCATION"DB13"
$SEC"1"
CDS_SEC"1";
"IO2 \B"
$PN"3"82;
"IO1 \B"
$PN"2"82;
"GND"
$PN"1"4;
%"UNIVERSAL_GND"
"1","(-3225,1425)","0","logical_power","I102";
;
HDL_POWER"T1_GND"
CDS_LIB"logical_power";
"A"4;
%"UNIVERSAL_GND"
"1","(-3225,900)","0","logical_power","I103";
;
HDL_POWER"T1_GND"
CDS_LIB"logical_power";
"A"19;
%"UNIVERSAL_GND"
"1","(2425,250)","0","logical_power","I104";
;
HDL_POWER"T1_GND"
CDS_LIB"logical_power";
"A"44;
%"UNIVERSAL_GND"
"1","(2425,-525)","0","logical_power","I105";
;
HDL_POWER"T1_GND"
CDS_LIB"logical_power";
"A"41;
%"TP_TDR_4P_FTS"
"1","(2025,475)","4","pure_quanta","I106";
;
PART_NUMBER"TP15"
PACK_TYPE"TH"
MATERIAL"EMPTY"
VALUE"TP_TDR_4P_DIP"
$LOCATION"X27"
NEEDS_NO_SIZE"TRUE"
CDS_LIB"pure_quanta"
CDS_LOCATION"X27"
$SEC"1"
CDS_SEC"1";
"S1"
$PN"1"63;
"P2 \B"
$PN"3"44;
"S2"
$PN"4"64;
"P1 \B"
$PN"2"44;
%"TP_TDR_4P_FTS"
"1","(2025,-300)","4","pure_quanta","I107";
;
PART_NUMBER"TP15"
VALUE"TP_TDR_4P_DIP"
MATERIAL"EMPTY"
PACK_TYPE"TH"
$LOCATION"X28"
NEEDS_NO_SIZE"TRUE"
CDS_LIB"pure_quanta"
CDS_LOCATION"X28"
$SEC"1"
CDS_SEC"1";
"S1"
$PN"1"84;
"P2 \B"
$PN"3"41;
"S2"
$PN"4"83;
"P1 \B"
$PN"2"41;
%"TP_TDR_4P_FTS"
"1","(700,475)","0","pure_quanta","I108";
;
PART_NUMBER"TP15"
VALUE"TP_TDR_4P_DIP"
PACK_TYPE"TH"
MATERIAL"EMPTY"
$LOCATION"X25"
NEEDS_NO_SIZE"TRUE"
CDS_LIB"pure_quanta"
CDS_LOCATION"X25"
$SEC"1"
CDS_SEC"1";
"S1"
$PN"1"64;
"P2 \B"
$PN"3"42;
"S2"
$PN"4"63;
"P1 \B"
$PN"2"42;
%"UNIVERSAL_GND"
"1","(275,250)","0","logical_power","I109";
;
HDL_POWER"T1_GND"
CDS_LIB"logical_power";
"A"42;
%"TP_TDR_4P_FTS"
"1","(3400,4250)","0","pure_quanta","I11";
;
PART_NUMBER"TP15"
PACK_TYPE"TH"
MATERIAL"EMPTY"
VALUE"TP_TDR_4P_DIP"
$LOCATION"X13"
NEEDS_NO_SIZE"TRUE"
CDS_LIB"pure_quanta"
CDS_LOCATION"X13"
$SEC"1"
CDS_SEC"1";
"S1"
$PN"1"87;
"P2 \B"
$PN"3"25;
"S2"
$PN"4"86;
"P1 \B"
$PN"2"25;
%"TP_TDR_4P_FTS"
"1","(700,-300)","0","pure_quanta","I110";
;
PART_NUMBER"TP15"
MATERIAL"EMPTY"
PACK_TYPE"TH"
VALUE"TP_TDR_4P_DIP"
$LOCATION"X26"
NEEDS_NO_SIZE"TRUE"
CDS_LIB"pure_quanta"
CDS_LOCATION"X26"
$SEC"1"
CDS_SEC"1";
"S1"
$PN"1"83;
"P2 \B"
$PN"3"1;
"S2"
$PN"4"84;
"P1 \B"
$PN"2"1;
%"UNIVERSAL_GND"
"1","(275,-525)","0","logical_power","I111";
;
HDL_POWER"T1_GND"
CDS_LIB"logical_power";
"A"1;
%"TP_TDR_4P_FTS"
"1","(4700,475)","4","pure_quanta","I112";
;
PART_NUMBER"TP15"
MATERIAL"EMPTY"
PACK_TYPE"TH"
VALUE"TP_TDR_4P_DIP"
$LOCATION"X31"
CDS_LIB"pure_quanta"
NEEDS_NO_SIZE"TRUE"
CDS_LOCATION"X31"
$SEC"1"
CDS_SEC"1";
"S1"
$PN"1"79;
"P2 \B"
$PN"3"30;
"S2"
$PN"4"60;
"P1 \B"
$PN"2"30;
%"UNIVERSAL_GND"
"1","(5100,250)","0","logical_power","I113";
;
HDL_POWER"T1_GND"
CDS_LIB"logical_power";
"A"30;
%"UNIVERSAL_GND"
"1","(5100,-525)","0","logical_power","I114";
;
HDL_POWER"T1_GND"
CDS_LIB"logical_power";
"A"36;
%"TP_TDR_4P_FTS"
"1","(4700,-300)","4","pure_quanta","I115";
;
PART_NUMBER"TP15"
MATERIAL"EMPTY"
PACK_TYPE"TH"
VALUE"TP_TDR_4P_DIP"
$LOCATION"X32"
CDS_LIB"pure_quanta"
NEEDS_NO_SIZE"TRUE"
CDS_LOCATION"X32"
$SEC"1"
CDS_SEC"1";
"S1"
$PN"1"75;
"P2 \B"
$PN"3"36;
"S2"
$PN"4"74;
"P1 \B"
$PN"2"36;
%"TP_TDR_4P_FTS"
"1","(3375,475)","0","pure_quanta","I116";
;
PART_NUMBER"TP15"
MATERIAL"EMPTY"
PACK_TYPE"TH"
VALUE"TP_TDR_4P_DIP"
$LOCATION"X29"
CDS_LIB"pure_quanta"
NEEDS_NO_SIZE"TRUE"
CDS_LOCATION"X29"
$SEC"1"
CDS_SEC"1";
"S1"
$PN"1"60;
"P2 \B"
$PN"3"37;
"S2"
$PN"4"79;
"P1 \B"
$PN"2"37;
%"TP_TDR_4P_FTS"
"1","(3375,-300)","0","pure_quanta","I117";
;
PART_NUMBER"TP15"
MATERIAL"EMPTY"
VALUE"TP_TDR_4P_DIP"
PACK_TYPE"TH"
$LOCATION"X30"
CDS_LIB"pure_quanta"
NEEDS_NO_SIZE"TRUE"
CDS_LOCATION"X30"
$SEC"1"
CDS_SEC"1";
"S1"
$PN"1"74;
"P2 \B"
$PN"3"38;
"S2"
$PN"4"75;
"P1 \B"
$PN"2"38;
%"UNIVERSAL_GND"
"1","(2950,250)","0","logical_power","I118";
;
HDL_POWER"T1_GND"
CDS_LIB"logical_power";
"A"37;
%"UNIVERSAL_GND"
"1","(2950,-525)","0","logical_power","I119";
;
HDL_POWER"T1_GND"
CDS_LIB"logical_power";
"A"38;
%"TP_TDR_4P_FTS"
"1","(3400,3475)","0","pure_quanta","I12";
;
PART_NUMBER"TP15"
PACK_TYPE"TH"
MATERIAL"EMPTY"
VALUE"TP_TDR_4P_DIP"
$LOCATION"X14"
NEEDS_NO_SIZE"TRUE"
CDS_LIB"pure_quanta"
CDS_LOCATION"X14"
$SEC"1"
CDS_SEC"1";
"S1"
$PN"1"89;
"P2 \B"
$PN"3"10;
"S2"
$PN"4"88;
"P1 \B"
$PN"2"10;
%"UNIVERSAL_GND"
"1","(2975,4025)","0","logical_power","I13";
;
HDL_POWER"T1_GND"
CDS_LIB"logical_power";
"A"25;
%"TP_TDR_4P_FTS"
"1","(3400,2700)","0","pure_quanta","I17";
;
PART_NUMBER"TP15"
MATERIAL"EMPTY"
VALUE"TP_TDR_4P_DIP"
PACK_TYPE"TH"
$LOCATION"X15"
CDS_LIB"pure_quanta"
NEEDS_NO_SIZE"TRUE"
CDS_LOCATION"X15"
$SEC"1"
CDS_SEC"1";
"S1"
$PN"1"90;
"P2 \B"
$PN"3"28;
"S2"
$PN"4"72;
"P1 \B"
$PN"2"28;
%"TP_TDR_4P_FTS"
"1","(3400,1925)","0","pure_quanta","I18";
;
PART_NUMBER"TP15"
PACK_TYPE"TH"
MATERIAL"EMPTY"
VALUE"TP_TDR_4P_DIP"
$LOCATION"X16"
NEEDS_NO_SIZE"TRUE"
CDS_LIB"pure_quanta"
CDS_LOCATION"X16"
$SEC"1"
CDS_SEC"1";
"S1"
$PN"1"57;
"P2 \B"
$PN"3"29;
"S2"
$PN"4"58;
"P1 \B"
$PN"2"29;
%"TP_TDR_4P_FTS"
"1","(3400,1150)","0","pure_quanta","I19";
;
PART_NUMBER"TP15"
PACK_TYPE"TH"
MATERIAL"EMPTY"
VALUE"TP_TDR_4P_DIP"
$LOCATION"X17"
NEEDS_NO_SIZE"TRUE"
CDS_LIB"pure_quanta"
CDS_LOCATION"X17"
$SEC"1"
CDS_SEC"1";
"S1"
$PN"1"78;
"P2 \B"
$PN"3"33;
"S2"
$PN"4"59;
"P1 \B"
$PN"2"33;
%"TP_TDR_4P_FTS"
"1","(2025,4250)","4","pure_quanta","I26";
;
PART_NUMBER"TP15"
MATERIAL"EMPTY"
PACK_TYPE"TH"
VALUE"TP_TDR_4P_DIP"
$LOCATION"X7"
CDS_LIB"pure_quanta"
NEEDS_NO_SIZE"TRUE"
CDS_LOCATION"X7"
$SEC"1"
CDS_SEC"1";
"S1"
$PN"1"70;
"P2 \B"
$PN"3"9;
"S2"
$PN"4"71;
"P1 \B"
$PN"2"9;
%"TP_TDR_4P_FTS"
"1","(2025,3475)","4","pure_quanta","I27";
;
PART_NUMBER"TP15"
MATERIAL"EMPTY"
VALUE"TP_TDR_4P_DIP"
PACK_TYPE"TH"
$LOCATION"X8"
CDS_LIB"pure_quanta"
NEEDS_NO_SIZE"TRUE"
CDS_LOCATION"X8"
$SEC"1"
CDS_SEC"1";
"S1"
$PN"1"91;
"P2 \B"
$PN"3"27;
"S2"
$PN"4"69;
"P1 \B"
$PN"2"27;
%"TP_TDR_4P_FTS"
"1","(700,4250)","0","pure_quanta","I28";
;
PART_NUMBER"TP15"
MATERIAL"EMPTY"
VALUE"TP_TDR_4P_DIP"
PACK_TYPE"TH"
$LOCATION"X1"
CDS_LIB"pure_quanta"
NEEDS_NO_SIZE"TRUE"
CDS_LOCATION"X1"
$SEC"1"
CDS_SEC"1";
"S1"
$PN"1"71;
"P2 \B"
$PN"3"47;
"S2"
$PN"4"70;
"P1 \B"
$PN"2"47;
%"TP_TDR_4P_FTS"
"1","(4725,4250)","4","pure_quanta","I3";
;
PART_NUMBER"TP15"
VALUE"TP_TDR_4P_DIP"
PACK_TYPE"TH"
MATERIAL"EMPTY"
$LOCATION"X19"
NEEDS_NO_SIZE"TRUE"
CDS_LIB"pure_quanta"
CDS_LOCATION"X19"
$SEC"1"
CDS_SEC"1";
"S1"
$PN"1"86;
"P2 \B"
$PN"3"45;
"S2"
$PN"4"87;
"P1 \B"
$PN"2"45;
%"TP_TDR_4P_FTS"
"1","(700,3475)","0","pure_quanta","I30";
;
PART_NUMBER"TP15"
PACK_TYPE"TH"
VALUE"TP_TDR_4P_DIP"
MATERIAL"EMPTY"
$LOCATION"X2"
CDS_LIB"pure_quanta"
NEEDS_NO_SIZE"TRUE"
CDS_LOCATION"X2"
$SEC"1"
CDS_SEC"1";
"S1"
$PN"1"69;
"P2 \B"
$PN"3"8;
"S2"
$PN"4"91;
"P1 \B"
$PN"2"8;
%"TP_TDR_4P_FTS"
"1","(2025,2700)","4","pure_quanta","I32";
;
PART_NUMBER"TP15"
PACK_TYPE"TH"
MATERIAL"EMPTY"
VALUE"TP_TDR_4P_DIP"
$LOCATION"X9"
NEEDS_NO_SIZE"TRUE"
CDS_LIB"pure_quanta"
CDS_LOCATION"X9"
$SEC"1"
CDS_SEC"1";
"S1"
$PN"1"85;
"P2 \B"
$PN"3"3;
"S2"
$PN"4"68;
"P1 \B"
$PN"2"3;
%"TP_TDR_4P_FTS"
"1","(2025,1925)","4","pure_quanta","I33";
;
PART_NUMBER"TP15"
VALUE"TP_TDR_4P_DIP"
PACK_TYPE"TH"
MATERIAL"EMPTY"
$LOCATION"X10"
NEEDS_NO_SIZE"TRUE"
CDS_LIB"pure_quanta"
CDS_LOCATION"X10"
$SEC"1"
CDS_SEC"1";
"S1"
$PN"1"67;
"P2 \B"
$PN"3"24;
"S2"
$PN"4"53;
"P1 \B"
$PN"2"24;
%"TP_TDR_4P_FTS"
"1","(2025,1150)","4","pure_quanta","I34";
;
PART_NUMBER"TP15"
MATERIAL"EMPTY"
PACK_TYPE"TH"
VALUE"TP_TDR_4P_DIP"
$LOCATION"X11"
NEEDS_NO_SIZE"TRUE"
CDS_LIB"pure_quanta"
CDS_LOCATION"X11"
$SEC"1"
CDS_SEC"1";
"S1"
$PN"1"65;
"P2 \B"
$PN"3"43;
"S2"
$PN"4"66;
"P1 \B"
$PN"2"43;
%"TP_TDR_4P_FTS"
"1","(700,2700)","0","pure_quanta","I35";
;
PART_NUMBER"TP15"
PACK_TYPE"TH"
MATERIAL"EMPTY"
VALUE"TP_TDR_4P_DIP"
$LOCATION"X3"
NEEDS_NO_SIZE"TRUE"
CDS_LIB"pure_quanta"
CDS_LOCATION"X3"
$SEC"1"
CDS_SEC"1";
"S1"
$PN"1"68;
"P2 \B"
$PN"3"48;
"S2"
$PN"4"85;
"P1 \B"
$PN"2"48;
%"TP_TDR_4P_FTS"
"1","(700,1925)","0","pure_quanta","I37";
;
PART_NUMBER"TP15"
VALUE"TP_TDR_4P_DIP"
PACK_TYPE"TH"
MATERIAL"EMPTY"
$LOCATION"X4"
NEEDS_NO_SIZE"TRUE"
CDS_LIB"pure_quanta"
CDS_LOCATION"X4"
$SEC"1"
CDS_SEC"1";
"S1"
$PN"1"53;
"P2 \B"
$PN"3"22;
"S2"
$PN"4"67;
"P1 \B"
$PN"2"22;
%"TP_TDR_4P_FTS"
"1","(700,1150)","0","pure_quanta","I39";
;
PART_NUMBER"TP15"
MATERIAL"EMPTY"
PACK_TYPE"TH"
VALUE"TP_TDR_4P_DIP"
$LOCATION"X5"
NEEDS_NO_SIZE"TRUE"
CDS_LIB"pure_quanta"
CDS_LOCATION"X5"
$SEC"1"
CDS_SEC"1";
"S1"
$PN"1"66;
"P2 \B"
$PN"3"23;
"S2"
$PN"4"65;
"P1 \B"
$PN"2"23;
%"TP_TDR_4P_FTS"
"1","(4725,3475)","4","pure_quanta","I4";
;
PART_NUMBER"TP15"
PACK_TYPE"TH"
MATERIAL"EMPTY"
VALUE"TP_TDR_4P_DIP"
$LOCATION"X20"
NEEDS_NO_SIZE"TRUE"
CDS_LIB"pure_quanta"
CDS_LOCATION"X20"
$SEC"1"
CDS_SEC"1";
"S1"
$PN"1"88;
"P2 \B"
$PN"3"46;
"S2"
$PN"4"89;
"P1 \B"
$PN"2"46;
%"TP_TDR_4P_FTS"
"1","(4700,-950)","4","pure_quanta","I42";
;
PART_NUMBER"TP15"
VALUE"TP_TDR_4P_DIP"
PACK_TYPE"TH"
MATERIAL"EMPTY"
$LOCATION"X24"
NEEDS_NO_SIZE"TRUE"
CDS_LIB"pure_quanta"
CDS_LOCATION"X24"
$SEC"1"
CDS_SEC"1";
"S1"
$PN"1"77;
"P2 \B"
$PN"3"32;
"S2"
$PN"4"76;
"P1 \B"
$PN"2"32;
%"TP_TDR_4P_FTS"
"1","(3375,-950)","0","pure_quanta","I43";
;
PART_NUMBER"TP15"
PACK_TYPE"TH"
VALUE"TP_TDR_4P_DIP"
MATERIAL"EMPTY"
$LOCATION"X18"
NEEDS_NO_SIZE"TRUE"
CDS_LIB"pure_quanta"
CDS_LOCATION"X18"
$SEC"1"
CDS_SEC"1";
"S1"
$PN"1"76;
"P2 \B"
$PN"3"31;
"S2"
$PN"4"77;
"P1 \B"
$PN"2"31;
%"TP_TDR_4P_FTS"
"1","(2025,-950)","4","pure_quanta","I46";
;
PART_NUMBER"TP15"
PACK_TYPE"TH"
VALUE"TP_TDR_4P_DIP"
MATERIAL"EMPTY"
$LOCATION"X12"
NEEDS_NO_SIZE"TRUE"
CDS_LIB"pure_quanta"
CDS_LOCATION"X12"
$SEC"1"
CDS_SEC"1";
"S1"
$PN"1"80;
"P2 \B"
$PN"3"39;
"S2"
$PN"4"81;
"P1 \B"
$PN"2"39;
%"TP_TDR_4P_FTS"
"1","(700,-950)","0","pure_quanta","I47";
;
PART_NUMBER"TP15"
PACK_TYPE"TH"
VALUE"TP_TDR_4P_DIP"
MATERIAL"EMPTY"
$LOCATION"X6"
NEEDS_NO_SIZE"TRUE"
CDS_LIB"pure_quanta"
CDS_LOCATION"X6"
$SEC"1"
CDS_SEC"1";
"S1"
$PN"1"81;
"P2 \B"
$PN"3"40;
"S2"
$PN"4"80;
"P1 \B"
$PN"2"40;
%"TDR_3P"
"2","(-1150,4275)","0","pure_quanta","I49";
;
PART_NUMBER"N_A"
PACK_TYPE"TH2"
$LOCATION"DB7"
MATERIAL"EMPTY"
CDS_LIB"pure_quanta"
CDS_LMAN_SYM_OUTLINE"-150,100,50,-100"
CDS_LOCATION"DB7"
$SEC"1"
CDS_SEC"1";
"IO2 \B"
$PN"3"92;
"IO1 \B"
$PN"2"92;
"GND"
$PN"1"21;
%"UNIVERSAL_GND"
"1","(-1500,4050)","0","logical_power","I50";
;
HDL_POWER"T1_GND"
CDS_LIB"logical_power";
"A"21;
%"TDR_3P"
"2","(-1150,3750)","0","pure_quanta","I51";
;
PART_NUMBER"N_A"
PACK_TYPE"TH2"
$LOCATION"DB8"
CDS_LMAN_SYM_OUTLINE"-150,100,50,-100"
CDS_LIB"pure_quanta"
MATERIAL"EMPTY"
CDS_LOCATION"DB8"
$SEC"1"
CDS_SEC"1";
"IO2 \B"
$PN"3"54;
"IO1 \B"
$PN"2"54;
"GND"
$PN"1"18;
%"UNIVERSAL_GND"
"1","(-1500,3525)","0","logical_power","I52";
;
HDL_POWER"T1_GND"
CDS_LIB"logical_power";
"A"18;
%"TDR_3P"
"2","(-1150,3225)","0","pure_quanta","I53";
;
PART_NUMBER"N_A"
PACK_TYPE"TH2"
$LOCATION"DB9"
CDS_LMAN_SYM_OUTLINE"-150,100,50,-100"
CDS_LIB"pure_quanta"
MATERIAL"EMPTY"
CDS_LOCATION"DB9"
$SEC"1"
CDS_SEC"1";
"IO2 \B"
$PN"3"62;
"IO1 \B"
$PN"2"62;
"GND"
$PN"1"17;
%"UNIVERSAL_GND"
"1","(-1500,3000)","0","logical_power","I54";
;
HDL_POWER"T1_GND"
CDS_LIB"logical_power";
"A"17;
%"TDR_3P"
"2","(-1150,2700)","0","pure_quanta","I55";
;
PART_NUMBER"N_A"
PACK_TYPE"TH2"
$LOCATION"DB10"
CDS_LMAN_SYM_OUTLINE"-150,100,50,-100"
CDS_LIB"pure_quanta"
MATERIAL"EMPTY"
CDS_LOCATION"DB10"
$SEC"1"
CDS_SEC"1";
"IO2 \B"
$PN"3"55;
"IO1 \B"
$PN"2"55;
"GND"
$PN"1"16;
%"UNIVERSAL_GND"
"1","(-1500,2475)","0","logical_power","I56";
;
HDL_POWER"T1_GND"
CDS_LIB"logical_power";
"A"16;
%"TDR_3P"
"2","(-1150,2175)","0","pure_quanta","I57";
;
PART_NUMBER"N_A"
PACK_TYPE"TH2"
$LOCATION"DB11"
MATERIAL"EMPTY"
CDS_LIB"pure_quanta"
CDS_LMAN_SYM_OUTLINE"-150,100,50,-100"
CDS_LOCATION"DB11"
$SEC"1"
CDS_SEC"1";
"IO2 \B"
$PN"3"56;
"IO1 \B"
$PN"2"56;
"GND"
$PN"1"15;
%"UNIVERSAL_GND"
"1","(-1500,1950)","0","logical_power","I58";
;
HDL_POWER"T1_GND"
CDS_LIB"logical_power";
"A"15;
%"UNIVERSAL_GND"
"1","(-1550,350)","0","logical_power","I59";
;
HDL_POWER"T1_GND"
CDS_LIB"logical_power";
"A"11;
%"TDR_3P"
"2","(-1200,575)","0","pure_quanta","I60";
;
PART_NUMBER"N_A"
PACK_TYPE"TH2"
$LOCATION"DB12"
MATERIAL"EMPTY"
CDS_LIB"pure_quanta"
CDS_LMAN_SYM_OUTLINE"-150,100,50,-100"
CDS_LOCATION"DB12"
$SEC"1"
CDS_SEC"1";
"IO2 \B"
$PN"3"50;
"IO1 \B"
$PN"2"50;
"GND"
$PN"1"11;
%"TDR_3P"
"2","(-2850,4275)","0","pure_quanta","I61";
;
PART_NUMBER"N_A"
PACK_TYPE"TH2"
$LOCATION"DB1"
CDS_LMAN_SYM_OUTLINE"-150,100,50,-100"
CDS_LIB"pure_quanta"
MATERIAL"EMPTY"
CDS_LOCATION"DB1"
$SEC"1"
CDS_SEC"1";
"IO2 \B"
$PN"3"93;
"IO1 \B"
$PN"2"93;
"GND"
$PN"1"2;
%"TDR_3P"
"2","(-2850,3750)","0","pure_quanta","I62";
;
PART_NUMBER"N_A"
PACK_TYPE"TH2"
$LOCATION"DB2"
MATERIAL"EMPTY"
CDS_LIB"pure_quanta"
CDS_LMAN_SYM_OUTLINE"-150,100,50,-100"
CDS_LOCATION"DB2"
$SEC"1"
CDS_SEC"1";
"IO2 \B"
$PN"3"61;
"IO1 \B"
$PN"2"61;
"GND"
$PN"1"7;
%"TDR_3P"
"2","(-2850,3225)","0","pure_quanta","I63";
;
PART_NUMBER"N_A"
PACK_TYPE"TH2"
$LOCATION"DB3"
MATERIAL"EMPTY"
CDS_LIB"pure_quanta"
CDS_LMAN_SYM_OUTLINE"-150,100,50,-100"
CDS_LOCATION"DB3"
$SEC"1"
CDS_SEC"1";
"IO2 \B"
$PN"3"94;
"IO1 \B"
$PN"2"94;
"GND"
$PN"1"20;
%"UNIVERSAL_GND"
"1","(-3200,4050)","0","logical_power","I64";
;
HDL_POWER"T1_GND"
CDS_LIB"logical_power";
"A"2;
%"UNIVERSAL_GND"
"1","(-3200,3525)","0","logical_power","I65";
;
HDL_POWER"T1_GND"
CDS_LIB"logical_power";
"A"7;
%"UNIVERSAL_GND"
"1","(-3200,3000)","0","logical_power","I66";
;
HDL_POWER"T1_GND"
CDS_LIB"logical_power";
"A"20;
%"TDR_3P"
"2","(-2850,2700)","0","pure_quanta","I67";
;
PART_NUMBER"N_A"
PACK_TYPE"TH2"
$LOCATION"DB4"
MATERIAL"EMPTY"
CDS_LIB"pure_quanta"
CDS_LMAN_SYM_OUTLINE"-150,100,50,-100"
CDS_LOCATION"DB4"
$SEC"1"
CDS_SEC"1";
"IO2 \B"
$PN"3"52;
"IO1 \B"
$PN"2"52;
"GND"
$PN"1"6;
%"TDR_3P"
"2","(-2850,2175)","0","pure_quanta","I68";
;
PART_NUMBER"N_A"
PACK_TYPE"TH2"
$LOCATION"DB5"
CDS_LMAN_SYM_OUTLINE"-150,100,50,-100"
CDS_LIB"pure_quanta"
MATERIAL"EMPTY"
CDS_LOCATION"DB5"
$SEC"1"
CDS_SEC"1";
"IO2 \B"
$PN"3"95;
"IO1 \B"
$PN"2"95;
"GND"
$PN"1"5;
%"TDR_3P"
"2","(-2900,575)","0","pure_quanta","I69";
;
PART_NUMBER"N_A"
PACK_TYPE"TH2"
$LOCATION"DB6"
CDS_LMAN_SYM_OUTLINE"-150,100,50,-100"
CDS_LIB"pure_quanta"
MATERIAL"EMPTY"
CDS_LOCATION"DB6"
$SEC"1"
CDS_SEC"1";
"IO2 \B"
$PN"3"96;
"IO1 \B"
$PN"2"96;
"GND"
$PN"1"12;
%"UNIVERSAL_GND"
"1","(-3200,2475)","0","logical_power","I70";
;
HDL_POWER"T1_GND"
CDS_LIB"logical_power";
"A"6;
%"UNIVERSAL_GND"
"1","(-3200,1950)","0","logical_power","I71";
;
HDL_POWER"T1_GND"
CDS_LIB"logical_power";
"A"5;
%"UNIVERSAL_GND"
"1","(-3250,350)","0","logical_power","I72";
;
HDL_POWER"T1_GND"
CDS_LIB"logical_power";
"A"12;
%"UNIVERSAL_GND"
"1","(5125,4025)","0","logical_power","I73";
;
HDL_POWER"T1_GND"
CDS_LIB"logical_power";
"A"45;
%"UNIVERSAL_GND"
"1","(5125,3250)","0","logical_power","I74";
;
HDL_POWER"T1_GND"
CDS_LIB"logical_power";
"A"46;
%"UNIVERSAL_GND"
"1","(5125,2475)","0","logical_power","I75";
;
HDL_POWER"T1_GND"
CDS_LIB"logical_power";
"A"26;
%"UNIVERSAL_GND"
"1","(5125,1700)","0","logical_power","I76";
;
HDL_POWER"T1_GND"
CDS_LIB"logical_power";
"A"35;
%"UNIVERSAL_GND"
"1","(5125,925)","0","logical_power","I77";
;
HDL_POWER"T1_GND"
CDS_LIB"logical_power";
"A"34;
%"UNIVERSAL_GND"
"1","(5100,-1150)","0","logical_power","I78";
;
HDL_POWER"T1_GND"
CDS_LIB"logical_power";
"A"32;
%"UNIVERSAL_GND"
"1","(2975,3250)","0","logical_power","I79";
;
HDL_POWER"T1_GND"
CDS_LIB"logical_power";
"A"10;
%"TP_TDR_4P_FTS"
"1","(4725,1925)","4","pure_quanta","I8";
;
PART_NUMBER"TP15"
MATERIAL"EMPTY"
VALUE"TP_TDR_4P_DIP"
PACK_TYPE"TH"
$LOCATION"X22"
NEEDS_NO_SIZE"TRUE"
CDS_LIB"pure_quanta"
CDS_LOCATION"X22"
$SEC"1"
CDS_SEC"1";
"S1"
$PN"1"58;
"P2 \B"
$PN"3"35;
"S2"
$PN"4"57;
"P1 \B"
$PN"2"35;
%"UNIVERSAL_GND"
"1","(2975,2475)","0","logical_power","I80";
;
HDL_POWER"T1_GND"
CDS_LIB"logical_power";
"A"28;
%"UNIVERSAL_GND"
"1","(2975,1700)","0","logical_power","I81";
;
HDL_POWER"T1_GND"
CDS_LIB"logical_power";
"A"29;
%"UNIVERSAL_GND"
"1","(2975,925)","0","logical_power","I82";
;
HDL_POWER"T1_GND"
CDS_LIB"logical_power";
"A"33;
%"UNIVERSAL_GND"
"1","(2950,-1150)","0","logical_power","I83";
;
HDL_POWER"T1_GND"
CDS_LIB"logical_power";
"A"31;
%"UNIVERSAL_GND"
"1","(2425,3250)","0","logical_power","I84";
;
HDL_POWER"T1_GND"
CDS_LIB"logical_power";
"A"27;
%"UNIVERSAL_GND"
"1","(275,3250)","0","logical_power","I85";
;
HDL_POWER"T1_GND"
CDS_LIB"logical_power";
"A"8;
%"UNIVERSAL_GND"
"1","(2425,4025)","0","logical_power","I86";
;
HDL_POWER"T1_GND"
CDS_LIB"logical_power";
"A"9;
%"UNIVERSAL_GND"
"1","(275,4025)","0","logical_power","I87";
;
HDL_POWER"T1_GND"
CDS_LIB"logical_power";
"A"47;
%"UNIVERSAL_GND"
"1","(275,2475)","0","logical_power","I88";
;
HDL_POWER"T1_GND"
CDS_LIB"logical_power";
"A"48;
%"UNIVERSAL_GND"
"1","(2425,2475)","0","logical_power","I89";
;
HDL_POWER"T1_GND"
CDS_LIB"logical_power";
"A"3;
%"TP_TDR_4P_FTS"
"1","(4725,2700)","4","pure_quanta","I9";
;
PART_NUMBER"TP15"
PACK_TYPE"TH"
VALUE"TP_TDR_4P_DIP"
MATERIAL"EMPTY"
$LOCATION"X21"
CDS_LIB"pure_quanta"
NEEDS_NO_SIZE"TRUE"
CDS_LOCATION"X21"
$SEC"1"
CDS_SEC"1";
"S1"
$PN"1"72;
"P2 \B"
$PN"3"26;
"S2"
$PN"4"90;
"P1 \B"
$PN"2"26;
%"UNIVERSAL_GND"
"1","(275,1700)","0","logical_power","I90";
;
HDL_POWER"T1_GND"
CDS_LIB"logical_power";
"A"22;
%"UNIVERSAL_GND"
"1","(2425,1700)","0","logical_power","I91";
;
HDL_POWER"T1_GND"
CDS_LIB"logical_power";
"A"24;
%"UNIVERSAL_GND"
"1","(275,925)","0","logical_power","I92";
;
HDL_POWER"T1_GND"
CDS_LIB"logical_power";
"A"23;
%"UNIVERSAL_GND"
"1","(2425,925)","0","logical_power","I93";
;
HDL_POWER"T1_GND"
CDS_LIB"logical_power";
"A"43;
%"UNIVERSAL_GND"
"1","(275,-1150)","0","logical_power","I94";
;
HDL_POWER"T1_GND"
CDS_LIB"logical_power";
"A"40;
%"UNIVERSAL_GND"
"1","(2425,-1150)","0","logical_power","I95";
;
HDL_POWER"T1_GND"
CDS_LIB"logical_power";
"A"39;
%"TDR_3P"
"2","(-2875,1125)","0","pure_quanta","I96";
;
PART_NUMBER"N_A"
PACK_TYPE"TH2"
$LOCATION"DB14"
CDS_LMAN_SYM_OUTLINE"-150,100,50,-100"
CDS_LIB"pure_quanta"
MATERIAL"EMPTY"
CDS_LOCATION"DB14"
$SEC"1"
CDS_SEC"1";
"IO2 \B"
$PN"3"49;
"IO1 \B"
$PN"2"49;
"GND"
$PN"1"19;
%"TDR_3P"
"2","(-1175,1650)","0","pure_quanta","I97";
;
PART_NUMBER"N_A"
PACK_TYPE"TH2"
$LOCATION"DB15"
CDS_LMAN_SYM_OUTLINE"-150,100,50,-100"
CDS_LIB"pure_quanta"
MATERIAL"EMPTY"
CDS_LOCATION"DB15"
$SEC"1"
CDS_SEC"1";
"IO2 \B"
$PN"3"73;
"IO1 \B"
$PN"2"73;
"GND"
$PN"1"14;
%"UNIVERSAL_GND"
"1","(-1525,1425)","0","logical_power","I98";
;
HDL_POWER"T1_GND"
CDS_LIB"logical_power";
"A"14;
%"TDR_3P"
"2","(-1175,1125)","0","pure_quanta","I99";
;
PART_NUMBER"N_A"
PACK_TYPE"TH2"
$LOCATION"DB16"
MATERIAL"EMPTY"
CDS_LIB"pure_quanta"
CDS_LMAN_SYM_OUTLINE"-150,100,50,-100"
CDS_LOCATION"DB16"
$SEC"1"
CDS_SEC"1";
"IO2 \B"
$PN"3"51;
"IO1 \B"
$PN"2"51;
"GND"
$PN"1"13;
END.
